# T6G (Grand Teton) — schematic netlist excerpt (pin names and nets, part order shuffled) for the footprints in the layout excerpt that follows; sources: Cadence DE-HDL packaged netlist, KiCad conversion of 04192023_DAF0TMB3IC0_F0TG_MB_C_brd_V02_OCP.brd

C307  Q_CAP  1UF 4V 20% X6S  pkg 0201  page 334 : A = P0V9_CPU1_RT1_2A ; B = GND
C104  Q_CAP  0.1UF 25V 10% X7R  pkg 0402  page 90 : A = P3V3_AUX ; B = GND
PC418_4  Q_CAP  22UF 4V 20% X6S  pkg C0805  page 219 : A = PVDDCR_CPU1_P1 ; B = GND

(kicad_pcb
	(version 20260206)
	(generator "pcbnew")
	(generator_version "10.0")
	(general
		(thickness 1.6)
		(legacy_teardrops no)
	)
	(paper "A4")
	(title_block
		(title "04192023_DAF0TMB3IC0_F0TG_MB_C_brd_V02_OCP.brd")
		(comment 1 "Grand Teton / footprints 4938-4940 of 8354")
	)
	(layers
		(0 "F.Cu" signal "TOP")
		(4 "In1.Cu" signal "GND")
		(6 "In2.Cu" signal "IN1")
		(8 "In3.Cu" signal "GND1")
		(10 "In4.Cu" signal "IN2")
		(12 "In5.Cu" signal "GND2")
		(14 "In6.Cu" signal "IN3")
		(16 "In7.Cu" signal "GND3")
		(18 "In8.Cu" signal "VCC")
		(20 "In9.Cu" signal "VCC1")
		(22 "In10.Cu" signal "GND4")
		(24 "In11.Cu" signal "IN4")
		(26 "In12.Cu" signal "GND5")
		(28 "In13.Cu" signal "IN5")
		(30 "In14.Cu" signal "GND6")
		(32 "In15.Cu" signal "IN6")
		(34 "In16.Cu" signal "GND7")
		(2 "B.Cu" signal "BOTTOM")
		(9 "F.Adhes" user "F.Adhesive")
		(11 "B.Adhes" user "B.Adhesive")
		(13 "F.Paste" user "Package Geometry/Pastemask Top")
		(15 "B.Paste" user "Package Geometry/Pastemask Bottom")
		(5 "F.SilkS" user "Ref Des/Silkscreen Top")
		(7 "B.SilkS" user "Ref Des/Silkscreen Bottom")
		(1 "F.Mask" user "Board Geometry/Soldermask Top")
		(3 "B.Mask" user "Board Geometry/Soldermask Bottom")
		(17 "Dwgs.User" user "User.Drawings")
		(19 "Cmts.User" user "User.Comments")
		(21 "Eco1.User" user "User.Eco1")
		(23 "Eco2.User" user "User.Eco2")
		(25 "Edge.Cuts" user "Board Geometry/Outline")
		(27 "Margin" user)
		(31 "F.CrtYd" user "Package Geometry/Place Bound Top")
		(29 "B.CrtYd" user "Package Geometry/Place Bound Bottom")
		(35 "F.Fab" user "Ref Des/Assembly Top")
		(33 "B.Fab" user "Ref Des/Assembly Bottom")
	)
	(footprint ""
		(layer "B.Cu")
		(at 276.436582 -193.99631)
		(property "Reference" "C104"
			(at 0 0 0)
			(layer "B.SilkS")
			(hide yes)
			(effects
				(font
					(size 1.27 1.27)
				)
				(justify mirror)
			)
		)
		(property "Value" ""
			(at 0 0 0)
			(layer "B.Fab")
			(effects
				(font
					(size 1.27 1.27)
				)
				(justify mirror)
			)
		)
		(duplicate_pad_numbers_are_jumpers no)
		(fp_line
			(start -0.7874 -0.4064)
			(end -0.7874 0.4064)
			(stroke
				(width 0.1524)
				(type default)
			)
			(layer "B.SilkS")
		)
		(fp_line
			(start -0.7874 0.4064)
			(end 0.7874 0.4064)
			(stroke
				(width 0.1524)
				(type default)
			)
			(layer "B.SilkS")
		)
		(fp_line
			(start 0.7874 -0.4064)
			(end -0.7874 -0.4064)
			(stroke
				(width 0.1524)
				(type default)
			)
			(layer "B.SilkS")
		)
		(fp_line
			(start 0.7874 0.4064)
			(end 0.7874 -0.4064)
			(stroke
				(width 0.1524)
				(type default)
			)
			(layer "B.SilkS")
		)
		(fp_line
			(start -0.67945 -0.3048)
			(end -0.67945 0.3048)
			(stroke
				(width 0.1)
				(type default)
			)
			(layer "B.Fab")
		)
		(fp_line
			(start -0.67945 0.3048)
			(end -0.120396 0.3048)
			(stroke
				(width 0.1)
				(type default)
			)
			(layer "B.Fab")
		)
		(fp_line
			(start -0.12065 -0.3048)
			(end -0.67945 -0.3048)
			(stroke
				(width 0.1)
				(type default)
			)
			(layer "B.Fab")
		)
		(fp_line
			(start -0.12065 -0.2794)
			(end -0.12065 -0.3048)
			(stroke
				(width 0.1)
				(type default)
			)
			(layer "B.Fab")
		)
		(fp_line
			(start -0.120396 0.2794)
			(end 0.12065 0.2794)
			(stroke
				(width 0.1)
				(type default)
			)
			(layer "B.Fab")
		)
		(fp_line
			(start -0.120396 0.3048)
			(end -0.120396 0.2794)
			(stroke
				(width 0.1)
				(type default)
			)
			(layer "B.Fab")
		)
		(fp_line
			(start 0.12065 -0.305054)
			(end 0.12065 -0.2794)
			(stroke
				(width 0.1)
				(type default)
			)
			(layer "B.Fab")
		)
		(fp_line
			(start 0.12065 -0.2794)
			(end -0.12065 -0.2794)
			(stroke
				(width 0.1)
				(type default)
			)
			(layer "B.Fab")
		)
		(fp_line
			(start 0.12065 0.2794)
			(end 0.12065 0.3048)
			(stroke
				(width 0.1)
				(type default)
			)
			(layer "B.Fab")
		)
		(fp_line
			(start 0.12065 0.3048)
			(end 0.67945 0.3048)
			(stroke
				(width 0.1)
				(type default)
			)
			(layer "B.Fab")
		)
		(fp_line
			(start 0.67945 -0.305054)
			(end 0.12065 -0.305054)
			(stroke
				(width 0.1)
				(type default)
			)
			(layer "B.Fab")
		)
		(fp_line
			(start 0.67945 0.3048)
			(end 0.67945 -0.305054)
			(stroke
				(width 0.1)
				(type default)
			)
			(layer "B.Fab")
		)
		(pad "1" smd circle
			(at 0.40005 0 180)
			(size 0 0)
			(layers "B.Cu" "B.Mask" "B.Paste")
			(net "P3V3_AUX")
		)
		(pad "2" smd circle
			(at -0.40005 0 180)
			(size 0 0)
			(layers "B.Cu" "B.Mask" "B.Paste")
			(net "GND")
		)
	)
	(footprint ""
		(layer "B.Cu")
		(at 95.506286 -386.766562 90)
		(property "Reference" "C307"
			(at 0 0 90)
			(layer "B.SilkS")
			(hide yes)
			(effects
				(font
					(size 1.27 1.27)
				)
				(justify mirror)
			)
		)
		(property "Value" ""
			(at 0 0 90)
			(layer "B.Fab")
			(effects
				(font
					(size 1.27 1.27)
				)
				(justify mirror)
			)
		)
		(duplicate_pad_numbers_are_jumpers no)
		(fp_line
			(start 0.299974 -0.150114)
			(end -0.299974 -0.150114)
			(stroke
				(width 0.1)
				(type default)
			)
			(layer "B.Fab")
		)
		(fp_line
			(start -0.299974 -0.150114)
			(end -0.299974 0.150114)
			(stroke
				(width 0.1)
				(type default)
			)
			(layer "B.Fab")
		)
		(fp_line
			(start 0.299974 0.150114)
			(end 0.299974 -0.150114)
			(stroke
				(width 0.1)
				(type default)
			)
			(layer "B.Fab")
		)
		(fp_line
			(start -0.299974 0.150114)
			(end 0.299974 0.150114)
			(stroke
				(width 0.1)
				(type default)
			)
			(layer "B.Fab")
		)
		(pad "1" smd rect
			(at 0.2667 0 270)
			(size 0.3048 0.381)
			(layers "B.Cu" "B.Mask" "B.Paste")
			(net "P0V9_CPU1_RT1_2A")
		)
		(pad "2" smd rect
			(at -0.2667 0 270)
			(size 0.3048 0.381)
			(layers "B.Cu" "B.Mask" "B.Paste")
			(net "GND")
		)
	)
	(footprint ""
		(layer "B.Cu")
		(at 64.911732 -338.086954 -90)
		(property "Reference" "PC418_4"
			(at 0 0 90)
			(layer "B.SilkS")
			(hide yes)
			(effects
				(font
					(size 1.27 1.27)
				)
				(justify mirror)
			)
		)
		(property "Value" ""
			(at 0 0 90)
			(layer "B.Fab")
			(effects
				(font
					(size 1.27 1.27)
				)
				(justify mirror)
			)
		)
		(duplicate_pad_numbers_are_jumpers no)
		(fp_line
			(start -1.524 0.762)
			(end 1.524 0.762)
			(stroke
				(width 0.1524)
				(type default)
			)
			(layer "B.SilkS")
		)
		(fp_line
			(start 1.524 0.762)
			(end 1.524 -0.762)
			(stroke
				(width 0.1524)
				(type default)
			)
			(layer "B.SilkS")
		)
		(fp_line
			(start -1.524 -0.762)
			(end -1.524 0.762)
			(stroke
				(width 0.1524)
				(type default)
			)
			(layer "B.SilkS")
		)
		(fp_line
			(start 1.524 -0.762)
			(end -1.524 -0.762)
			(stroke
				(width 0.1524)
				(type default)
			)
			(layer "B.SilkS")
		)
		(fp_line
			(start -1.1049 0.724916)
			(end -1.1049 -0.724916)
			(stroke
				(width 0.1)
				(type default)
			)
			(layer "B.Fab")
		)
		(fp_line
			(start 1.1049 0.724916)
			(end -1.1049 0.724916)
			(stroke
				(width 0.1)
				(type default)
			)
			(layer "B.Fab")
		)
		(fp_line
			(start -1.1049 -0.724916)
			(end 1.1049 -0.724916)
			(stroke
				(width 0.1)
				(type default)
			)
			(layer "B.Fab")
		)
		(fp_line
			(start 1.1049 -0.724916)
			(end 1.1049 0.724916)
			(stroke
				(width 0.1)
				(type default)
			)
			(layer "B.Fab")
		)
		(pad "1" smd rect
			(at 0.889 0 270)
			(size 1.016 1.27)
			(layers "B.Cu" "B.Mask" "B.Paste")
			(net "PVDDCR_CPU1_P1")
		)
		(pad "2" smd rect
			(at -0.889 0 270)
			(size 1.016 1.27)
			(layers "B.Cu" "B.Mask" "B.Paste")
			(net "GND")
		)
	)
)
